(kicad_pcb
	(version 20241229)
	(generator "pcbnew")
	(generator_version "9.0")
	(general
		(thickness 1.6642)
		(legacy_teardrops no)
	)
	(paper "A3")
	(title_block
		(title "PolarFire SoM")
		(date "2025-07-22")
		(rev "1.1.4")
		(company "Antmicro Ltd")
		(comment 1 "www.antmicro.com")
		(comment 9 "footprints 182-186 of 470")
	)
	(layers
		(0 "F.Cu" mixed)
		(4 "In1.Cu" power)
		(6 "In2.Cu" signal)
		(8 "In3.Cu" power)
		(10 "In4.Cu" signal)
		(12 "In5.Cu" power)
		(14 "In6.Cu" power)
		(16 "In7.Cu" signal)
		(18 "In8.Cu" power)
		(20 "In9.Cu" signal)
		(22 "In10.Cu" power)
		(24 "In11.Cu" signal)
		(26 "In12.Cu" signal)
		(2 "B.Cu" mixed)
		(9 "F.Adhes" user "F.Adhesive")
		(11 "B.Adhes" user "B.Adhesive")
		(13 "F.Paste" user)
		(15 "B.Paste" user)
		(5 "F.SilkS" user "F.Silkscreen")
		(7 "B.SilkS" user "B.Silkscreen")
		(1 "F.Mask" user)
		(3 "B.Mask" user)
		(17 "Dwgs.User" user "User.Drawings")
		(19 "Cmts.User" user "User.Comments")
		(21 "Eco1.User" user "User.Eco1")
		(23 "Eco2.User" user "User.Eco2")
		(25 "Edge.Cuts" user)
		(27 "Margin" user)
		(31 "F.CrtYd" user "F.Courtyard")
		(29 "B.CrtYd" user "B.Courtyard")
		(35 "F.Fab" user)
		(33 "B.Fab" user)
	)
	(footprint "antmicro-footprints:C_0402_1005Metric"
		(layer "B.Cu")
		(at 201.4 147.45)
		(descr "Capacitor SMD 0402")
		(tags "capacitor SMD 0402")
		(property "Reference" "C208"
			(at -1.74 2.53 0)
			(layer "B.SilkS")
			(effects
				(font
					(size 0.7 0.7)
					(thickness 0.15)
				)
				(justify right bottom mirror)
			)
		)
		(property "Value" "C_10u_10V_0402"
			(at -1.022927 -2.155213 0)
			(layer "B.Fab")
			(hide yes)
			(effects
				(font
					(size 0.7 0.7)
					(thickness 0.15)
				)
				(justify right bottom mirror)
			)
		)
		(property "Datasheet" "https://www.murata.com/products/productdetail?partno=GRM155R61A106ME11%23"
			(at 0 0 0)
			(layer "F.Fab")
			(hide yes)
			(effects
				(font
					(size 1.27 1.27)
					(thickness 0.15)
				)
			)
		)
		(property "Description" "Multilayer Ceramic Capacitors MLCC - SMD/SMT 10 uF 10 VDC 20% 0402 X5R"
			(at 0 0 0)
			(layer "F.Fab")
			(hide yes)
			(effects
				(font
					(size 1.27 1.27)
					(thickness 0.15)
				)
			)
		)
		(property "Author" "Antmicro"
			(at 0 0 0)
			(layer "B.Fab")
			(hide yes)
			(effects
				(font
					(size 1 1)
					(thickness 0.15)
				)
				(justify mirror)
			)
		)
		(property "Dielectric" "X5R"
			(at 0 0 0)
			(layer "B.Fab")
			(hide yes)
			(effects
				(font
					(size 1 1)
					(thickness 0.15)
				)
				(justify mirror)
			)
		)
		(property "License" "Apache-2.0"
			(at 0 0 0)
			(layer "B.Fab")
			(hide yes)
			(effects
				(font
					(size 1 1)
					(thickness 0.15)
				)
				(justify mirror)
			)
		)
		(property "MPN" "GRM155R61A106ME11D"
			(at 0 0 0)
			(layer "B.Fab")
			(hide yes)
			(effects
				(font
					(size 1 1)
					(thickness 0.15)
				)
				(justify mirror)
			)
		)
		(property "Manufacturer" "Murata"
			(at 0 0 0)
			(layer "B.Fab")
			(hide yes)
			(effects
				(font
					(size 1 1)
					(thickness 0.15)
				)
				(justify mirror)
			)
		)
		(property "Public" ""
			(at 0 0 0)
			(layer "B.Fab")
			(hide yes)
			(effects
				(font
					(size 1 1)
					(thickness 0.15)
				)
				(justify mirror)
			)
		)
		(property "Val" "10u"
			(at 0 0 0)
			(layer "B.Fab")
			(hide yes)
			(effects
				(font
					(size 1 1)
					(thickness 0.15)
				)
				(justify mirror)
			)
		)
		(property "Voltage" "10V"
			(at 0 0 0)
			(layer "B.Fab")
			(hide yes)
			(effects
				(font
					(size 1 1)
					(thickness 0.15)
				)
				(justify mirror)
			)
		)
		(sheetname "/MIPI CrossLink/")
		(sheetfile "crosslink.kicad_sch")
		(attr smd)
		(fp_rect
			(start -0.925 0.47)
			(end 0.925 -0.47)
			(stroke
				(width 0.05)
				(type default)
			)
			(fill no)
			(layer "B.CrtYd")
		)
		(fp_line
			(start -0.494 -0.248)
			(end -0.494 0.25)
			(stroke
				(width 0.15)
				(type solid)
			)
			(layer "B.Fab")
		)
		(fp_line
			(start -0.494 0.25)
			(end 0.504 0.25)
			(stroke
				(width 0.15)
				(type solid)
			)
			(layer "B.Fab")
		)
		(fp_line
			(start 0.504 -0.248)
			(end -0.494 -0.248)
			(stroke
				(width 0.15)
				(type solid)
			)
			(layer "B.Fab")
		)
		(fp_line
			(start 0.504 0.25)
			(end 0.504 -0.248)
			(stroke
				(width 0.15)
				(type solid)
			)
			(layer "B.Fab")
		)
		(fp_text user "License: Apache-2.0"
			(at -0.939 -5.799 180)
			(layer "B.Fab")
			(effects
				(font
					(size 0.7 0.7)
					(thickness 0.15)
				)
				(justify left bottom mirror)
			)
		)
		(fp_text user "${REFERENCE}"
			(at -0.939 -4.599 180)
			(layer "B.Fab")
			(effects
				(font
					(size 0.7 0.7)
					(thickness 0.15)
				)
				(justify left bottom mirror)
			)
		)
		(fp_text user "Author: Antmicro"
			(at -0.939 -3.399 180)
			(layer "B.Fab")
			(effects
				(font
					(size 0.7 0.7)
					(thickness 0.15)
				)
				(justify left bottom mirror)
			)
		)
		(pad "1" smd roundrect
			(at -0.48 0)
			(size 0.59 0.64)
			(layers "B.Cu" "B.Mask" "B.Paste")
			(roundrect_rratio 0.25)
			(net 417 "GND")
			(pintype "passive")
		)
		(pad "2" smd roundrect
			(at 0.48 0)
			(size 0.59 0.64)
			(layers "B.Cu" "B.Mask" "B.Paste")
			(roundrect_rratio 0.25)
			(net 203 "/MIPI CrossLink/CL_VCCA_DPHY0")
			(pintype "passive")
		)
	)
	(footprint "antmicro-footprints:R_0402_1005Metric"
		(layer "B.Cu")
		(at 184.275 152.05 -90)
		(descr "Resistor SMD 0402")
		(tags "resistor SMD 0402")
		(property "Reference" "R19"
			(at -2.95 -0.425 90)
			(layer "B.SilkS")
			(effects
				(font
					(size 0.7 0.7)
					(thickness 0.15)
				)
				(justify left bottom mirror)
			)
		)
		(property "Value" "R_205k_0402"
			(at -1.011843 -1.772047 90)
			(layer "B.Fab")
			(hide yes)
			(effects
				(font
					(size 0.7 0.7)
					(thickness 0.15)
				)
				(justify left bottom mirror)
			)
		)
		(property "Datasheet" "https://www.bourns.com/docs/product-datasheets/cr.pdf"
			(at 0 0 270)
			(layer "F.Fab")
			(hide yes)
			(effects
				(font
					(size 1.27 1.27)
					(thickness 0.15)
				)
			)
		)
		(property "Description" "SMD Chip Resistor"
			(at 0 0 270)
			(layer "F.Fab")
			(hide yes)
			(effects
				(font
					(size 1.27 1.27)
					(thickness 0.15)
				)
			)
		)
		(property "Author" "Antmicro"
			(at 32.225 336.325 0)
			(layer "B.Fab")
			(hide yes)
			(effects
				(font
					(size 1 1)
					(thickness 0.15)
				)
				(justify mirror)
			)
		)
		(property "License" "Apache-2.0"
			(at 32.225 336.325 0)
			(layer "B.Fab")
			(hide yes)
			(effects
				(font
					(size 1 1)
					(thickness 0.15)
				)
				(justify mirror)
			)
		)
		(property "MPN" "CR0402-FX-2053GLF"
			(at 32.225 336.325 0)
			(layer "B.Fab")
			(hide yes)
			(effects
				(font
					(size 1 1)
					(thickness 0.15)
				)
				(justify mirror)
			)
		)
		(property "Manufacturer" "Bourns"
			(at 32.225 336.325 0)
			(layer "B.Fab")
			(hide yes)
			(effects
				(font
					(size 1 1)
					(thickness 0.15)
				)
				(justify mirror)
			)
		)
		(property "Public" ""
			(at 32.225 336.325 0)
			(layer "B.Fab")
			(hide yes)
			(effects
				(font
					(size 1 1)
					(thickness 0.15)
				)
				(justify mirror)
			)
		)
		(property "Tolerance" "1%"
			(at 32.225 336.325 0)
			(layer "B.Fab")
			(hide yes)
			(effects
				(font
					(size 1 1)
					(thickness 0.15)
				)
				(justify mirror)
			)
		)
		(property "Val" "205k"
			(at 32.225 336.325 0)
			(layer "B.Fab")
			(hide yes)
			(effects
				(font
					(size 1 1)
					(thickness 0.15)
				)
				(justify mirror)
			)
		)
		(sheetname "/Supply/")
		(sheetfile "supply.kicad_sch")
		(attr smd)
		(fp_rect
			(start -0.925 0.47)
			(end 0.925 -0.47)
			(stroke
				(width 0.05)
				(type default)
			)
			(fill no)
			(layer "B.CrtYd")
		)
		(fp_rect
			(start -0.5 0.25)
			(end 0.5 -0.25)
			(stroke
				(width 0.15)
				(type solid)
			)
			(fill no)
			(layer "B.Fab")
		)
		(fp_text user "${REFERENCE}"
			(at -0.95 -3.168 90)
			(layer "B.Fab")
			(effects
				(font
					(size 0.7 0.7)
					(thickness 0.15)
				)
				(justify left bottom mirror)
			)
		)
		(fp_text user "License: Apache-2.0"
			(at -0.95 -5.169 90)
			(layer "B.Fab")
			(effects
				(font
					(size 0.7 0.7)
					(thickness 0.15)
				)
				(justify left bottom mirror)
			)
		)
		(fp_text user "Author: Antmicro"
			(at -0.95 -4.169 90)
			(layer "B.Fab")
			(effects
				(font
					(size 0.7 0.7)
					(thickness 0.15)
				)
				(justify left bottom mirror)
			)
		)
		(pad "1" smd roundrect
			(at -0.48 0 270)
			(size 0.59 0.64)
			(layers "B.Cu" "B.Mask" "B.Paste")
			(roundrect_rratio 0.25)
			(net 417 "GND")
			(pintype "passive")
		)
		(pad "2" smd roundrect
			(at 0.48 0 270)
			(size 0.59 0.64)
			(layers "B.Cu" "B.Mask" "B.Paste")
			(roundrect_rratio 0.25)
			(net 14 "Net-(C111-Pad1)")
			(pintype "passive")
		)
	)
	(footprint "antmicro-footprints:R_0402_1005Metric"
		(layer "B.Cu")
		(at 178.75 145.55 -90)
		(descr "Resistor SMD 0402")
		(tags "resistor SMD 0402")
		(property "Reference" "R69"
			(at 3.62 -1.32 90)
			(layer "B.SilkS")
			(effects
				(font
					(size 0.7 0.7)
					(thickness 0.15)
				)
				(justify left bottom mirror)
			)
		)
		(property "Value" "R_100k_0402"
			(at -1.011843 -1.772047 90)
			(layer "B.Fab")
			(hide yes)
			(effects
				(font
					(size 0.7 0.7)
					(thickness 0.15)
				)
				(justify left bottom mirror)
			)
		)
		(property "Datasheet" "https://www.bourns.com/docs/product-datasheets/cr.pdf"
			(at 0 0 270)
			(layer "F.Fab")
			(hide yes)
			(effects
				(font
					(size 1.27 1.27)
					(thickness 0.15)
				)
			)
		)
		(property "Description" "SMD Chip Resistor, 100 kohm, ± 1%, 62.5 mW, 0402 [1005 Metric], Thick Film, General Purpose"
			(at 0 0 270)
			(layer "F.Fab")
			(hide yes)
			(effects
				(font
					(size 1.27 1.27)
					(thickness 0.15)
				)
			)
		)
		(property "Author" "Antmicro"
			(at 33.2 324.3 0)
			(layer "B.Fab")
			(hide yes)
			(effects
				(font
					(size 1 1)
					(thickness 0.15)
				)
				(justify mirror)
			)
		)
		(property "License" "Apache-2.0"
			(at 33.2 324.3 0)
			(layer "B.Fab")
			(hide yes)
			(effects
				(font
					(size 1 1)
					(thickness 0.15)
				)
				(justify mirror)
			)
		)
		(property "MPN" "CR0402-FX-1003GLF"
			(at 33.2 324.3 0)
			(layer "B.Fab")
			(hide yes)
			(effects
				(font
					(size 1 1)
					(thickness 0.15)
				)
				(justify mirror)
			)
		)
		(property "Manufacturer" "Bourns"
			(at 33.2 324.3 0)
			(layer "B.Fab")
			(hide yes)
			(effects
				(font
					(size 1 1)
					(thickness 0.15)
				)
				(justify mirror)
			)
		)
		(property "Public" ""
			(at 33.2 324.3 0)
			(layer "B.Fab")
			(hide yes)
			(effects
				(font
					(size 1 1)
					(thickness 0.15)
				)
				(justify mirror)
			)
		)
		(property "Tolerance" "1%"
			(at 33.2 324.3 0)
			(layer "B.Fab")
			(hide yes)
			(effects
				(font
					(size 1 1)
					(thickness 0.15)
				)
				(justify mirror)
			)
		)
		(property "Val" "100k"
			(at 33.2 324.3 0)
			(layer "B.Fab")
			(hide yes)
			(effects
				(font
					(size 1 1)
					(thickness 0.15)
				)
				(justify mirror)
			)
		)
		(sheetname "/Supply/")
		(sheetfile "supply.kicad_sch")
		(attr smd)
		(fp_rect
			(start -0.925 0.47)
			(end 0.925 -0.47)
			(stroke
				(width 0.05)
				(type default)
			)
			(fill no)
			(layer "B.CrtYd")
		)
		(fp_rect
			(start -0.5 0.25)
			(end 0.5 -0.25)
			(stroke
				(width 0.15)
				(type solid)
			)
			(fill no)
			(layer "B.Fab")
		)
		(fp_text user "Author: Antmicro"
			(at -0.95 -4.169 90)
			(layer "B.Fab")
			(effects
				(font
					(size 0.7 0.7)
					(thickness 0.15)
				)
				(justify left bottom mirror)
			)
		)
		(fp_text user "License: Apache-2.0"
			(at -0.95 -5.169 90)
			(layer "B.Fab")
			(effects
				(font
					(size 0.7 0.7)
					(thickness 0.15)
				)
				(justify left bottom mirror)
			)
		)
		(fp_text user "${REFERENCE}"
			(at -0.95 -3.168 90)
			(layer "B.Fab")
			(effects
				(font
					(size 0.7 0.7)
					(thickness 0.15)
				)
				(justify left bottom mirror)
			)
		)
		(pad "1" smd roundrect
			(at -0.48 0 270)
			(size 0.59 0.64)
			(layers "B.Cu" "B.Mask" "B.Paste")
			(roundrect_rratio 0.25)
			(net 417 "GND")
			(pintype "passive")
		)
		(pad "2" smd roundrect
			(at 0.48 0 270)
			(size 0.59 0.64)
			(layers "B.Cu" "B.Mask" "B.Paste")
			(roundrect_rratio 0.25)
			(net 656 "/Supply/PG")
			(pintype "passive")
		)
	)
	(footprint "antmicro-footprints:C_0402_1005Metric"
		(layer "B.Cu")
		(at 191.384 125.101 180)
		(descr "Capacitor SMD 0402")
		(tags "capacitor SMD 0402")
		(property "Reference" "C1"
			(at -1.116 0.526 0)
			(layer "B.SilkS")
			(effects
				(font
					(size 0.7 0.7)
					(thickness 0.15)
				)
				(justify left bottom mirror)
			)
		)
		(property "Value" "C_1n_0402"
			(at -1.022927 -2.155213 0)
			(layer "B.Fab")
			(hide yes)
			(effects
				(font
					(size 0.7 0.7)
					(thickness 0.15)
				)
				(justify left bottom mirror)
			)
		)
		(property "Datasheet" "https://www.murata.com/products/productdetail?partno=GRM1555C1H102JA01%23"
			(at 0 0 180)
			(layer "F.Fab")
			(hide yes)
			(effects
				(font
					(size 1.27 1.27)
					(thickness 0.15)
				)
			)
		)
		(property "Description" "SMD Multilayer Ceramic Capacitor, 1000 pF, 50 V, 0402 [1005 Metric], ± 5%, C0G / NP0, GRM Series"
			(at 0 0 180)
			(layer "F.Fab")
			(hide yes)
			(effects
				(font
					(size 1.27 1.27)
					(thickness 0.15)
				)
			)
		)
		(property "Author" "Antmicro"
			(at 382.768 250.202 0)
			(layer "B.Fab")
			(hide yes)
			(effects
				(font
					(size 1 1)
					(thickness 0.15)
				)
				(justify mirror)
			)
		)
		(property "Dielectric" "C0G"
			(at 382.768 250.202 0)
			(layer "B.Fab")
			(hide yes)
			(effects
				(font
					(size 1 1)
					(thickness 0.15)
				)
				(justify mirror)
			)
		)
		(property "License" "Apache-2.0"
			(at 382.768 250.202 0)
			(layer "B.Fab")
			(hide yes)
			(effects
				(font
					(size 1 1)
					(thickness 0.15)
				)
				(justify mirror)
			)
		)
		(property "MPN" "GRM1555C1H102JA01D"
			(at 382.768 250.202 0)
			(layer "B.Fab")
			(hide yes)
			(effects
				(font
					(size 1 1)
					(thickness 0.15)
				)
				(justify mirror)
			)
		)
		(property "Manufacturer" "Murata"
			(at 382.768 250.202 0)
			(layer "B.Fab")
			(hide yes)
			(effects
				(font
					(size 1 1)
					(thickness 0.15)
				)
				(justify mirror)
			)
		)
		(property "Public" ""
			(at 382.768 250.202 0)
			(layer "B.Fab")
			(hide yes)
			(effects
				(font
					(size 1 1)
					(thickness 0.15)
				)
				(justify mirror)
			)
		)
		(property "Val" "1n"
			(at 382.768 250.202 0)
			(layer "B.Fab")
			(hide yes)
			(effects
				(font
					(size 1 1)
					(thickness 0.15)
				)
				(justify mirror)
			)
		)
		(property "Voltage" "50V"
			(at 382.768 250.202 0)
			(layer "B.Fab")
			(hide yes)
			(effects
				(font
					(size 1 1)
					(thickness 0.15)
				)
				(justify mirror)
			)
		)
		(sheetname "/FPGA Supply/")
		(sheetfile "fpga-supply.kicad_sch")
		(attr smd)
		(fp_rect
			(start -0.925 0.47)
			(end 0.925 -0.47)
			(stroke
				(width 0.05)
				(type default)
			)
			(fill no)
			(layer "B.CrtYd")
		)
		(fp_line
			(start 0.504 0.25)
			(end 0.504 -0.248)
			(stroke
				(width 0.15)
				(type solid)
			)
			(layer "B.Fab")
		)
		(fp_line
			(start 0.504 -0.248)
			(end -0.494 -0.248)
			(stroke
				(width 0.15)
				(type solid)
			)
			(layer "B.Fab")
		)
		(fp_line
			(start -0.494 0.25)
			(end 0.504 0.25)
			(stroke
				(width 0.15)
				(type solid)
			)
			(layer "B.Fab")
		)
		(fp_line
			(start -0.494 -0.248)
			(end -0.494 0.25)
			(stroke
				(width 0.15)
				(type solid)
			)
			(layer "B.Fab")
		)
		(fp_text user "Author: Antmicro"
			(at -0.939 -3.399 0)
			(layer "B.Fab")
			(effects
				(font
					(size 0.7 0.7)
					(thickness 0.15)
				)
				(justify left bottom mirror)
			)
		)
		(fp_text user "License: Apache-2.0"
			(at -0.939 -5.799 0)
			(layer "B.Fab")
			(effects
				(font
					(size 0.7 0.7)
					(thickness 0.15)
				)
				(justify left bottom mirror)
			)
		)
		(fp_text user "${REFERENCE}"
			(at -0.939 -4.599 0)
			(layer "B.Fab")
			(effects
				(font
					(size 0.7 0.7)
					(thickness 0.15)
				)
				(justify left bottom mirror)
			)
		)
		(pad "1" smd roundrect
			(at -0.48 0 180)
			(size 0.59 0.64)
			(layers "B.Cu" "B.Mask" "B.Paste")
			(roundrect_rratio 0.25)
			(net 417 "GND")
			(pintype "passive")
		)
		(pad "2" smd roundrect
			(at 0.48 0 180)
			(size 0.59 0.64)
			(layers "B.Cu" "B.Mask" "B.Paste")
			(roundrect_rratio 0.25)
			(net 2 "+1V1")
			(pintype "passive")
		)
	)
	(footprint "antmicro-footprints:R_0402_1005Metric"
		(layer "B.Cu")
		(at 225.075 147.825 90)
		(descr "Resistor SMD 0402")
		(tags "resistor SMD 0402")
		(property "Reference" "R99"
			(at 0.915 2.465 90)
			(layer "B.SilkS")
			(effects
				(font
					(size 0.7 0.7)
					(thickness 0.15)
				)
				(justify left bottom mirror)
			)
		)
		(property "Value" "R_0R_0402"
			(at -1.011843 -1.772047 270)
			(layer "B.Fab")
			(hide yes)
			(effects
				(font
					(size 0.7 0.7)
					(thickness 0.15)
				)
				(justify left bottom mirror)
			)
		)
		(property "Datasheet" "https://industrial.panasonic.com/cdbs/www-data/pdf/RDA0000/AOA0000C301.pdf"
			(at 0 0 90)
			(layer "F.Fab")
			(hide yes)
			(effects
				(font
					(size 1.27 1.27)
					(thickness 0.15)
				)
			)
		)
		(property "Description" "SMD Chip Resistor, Jumper, 0 ohm, 100 mW, 0402 [1005 Metric], Thick Film, General Purpose"
			(at 0 0 90)
			(layer "F.Fab")
			(hide yes)
			(effects
				(font
					(size 1.27 1.27)
					(thickness 0.15)
				)
			)
		)
		(property "Author" "Antmicro"
			(at 372.9 -77.25 0)
			(layer "B.Fab")
			(hide yes)
			(effects
				(font
					(size 1 1)
					(thickness 0.15)
				)
				(justify mirror)
			)
		)
		(property "Current" "1A"
			(at 372.9 -77.25 0)
			(layer "B.Fab")
			(hide yes)
			(effects
				(font
					(size 1 1)
					(thickness 0.15)
				)
				(justify mirror)
			)
		)
		(property "License" "Apache-2.0"
			(at 372.9 -77.25 0)
			(layer "B.Fab")
			(hide yes)
			(effects
				(font
					(size 1 1)
					(thickness 0.15)
				)
				(justify mirror)
			)
		)
		(property "MPN" "ERJ2GE0R00X"
			(at 372.9 -77.25 0)
			(layer "B.Fab")
			(hide yes)
			(effects
				(font
					(size 1 1)
					(thickness 0.15)
				)
				(justify mirror)
			)
		)
		(property "Manufacturer" "Panasonic"
			(at 372.9 -77.25 0)
			(layer "B.Fab")
			(hide yes)
			(effects
				(font
					(size 1 1)
					(thickness 0.15)
				)
				(justify mirror)
			)
		)
		(property "Public" ""
			(at 372.9 -77.25 0)
			(layer "B.Fab")
			(hide yes)
			(effects
				(font
					(size 1 1)
					(thickness 0.15)
				)
				(justify mirror)
			)
		)
		(property "Tolerance" "~"
			(at 372.9 -77.25 0)
			(layer "B.Fab")
			(hide yes)
			(effects
				(font
					(size 1 1)
					(thickness 0.15)
				)
				(justify mirror)
			)
		)
		(property "Val" "0R"
			(at 372.9 -77.25 0)
			(layer "B.Fab")
			(hide yes)
			(effects
				(font
					(size 1 1)
					(thickness 0.15)
				)
				(justify mirror)
			)
		)
		(sheetname "/FPGA MSSIO/")
		(sheetfile "fpga-mssio.kicad_sch")
		(attr smd)
		(fp_rect
			(start -0.925 0.47)
			(end 0.925 -0.47)
			(stroke
				(width 0.05)
				(type default)
			)
			(fill no)
			(layer "B.CrtYd")
		)
		(fp_rect
			(start -0.5 0.25)
			(end 0.5 -0.25)
			(stroke
				(width 0.15)
				(type solid)
			)
			(fill no)
			(layer "B.Fab")
		)
		(fp_text user "${REFERENCE}"
			(at -0.95 -3.168 270)
			(layer "B.Fab")
			(effects
				(font
					(size 0.7 0.7)
					(thickness 0.15)
				)
				(justify left bottom mirror)
			)
		)
		(fp_text user "License: Apache-2.0"
			(at -0.95 -5.169 270)
			(layer "B.Fab")
			(effects
				(font
					(size 0.7 0.7)
					(thickness 0.15)
				)
				(justify left bottom mirror)
			)
		)
		(fp_text user "Author: Antmicro"
			(at -0.95 -4.169 270)
			(layer "B.Fab")
			(effects
				(font
					(size 0.7 0.7)
					(thickness 0.15)
				)
				(justify left bottom mirror)
			)
		)
		(pad "1" smd roundrect
			(at -0.48 0 90)
			(size 0.59 0.64)
			(layers "B.Cu" "B.Mask" "B.Paste")
			(roundrect_rratio 0.25)
			(net 285 "Net-(U1C-MSSIO35B2)")
			(pintype "passive")
		)
		(pad "2" smd roundrect
			(at 0.48 0 90)
			(size 0.59 0.64)
			(layers "B.Cu" "B.Mask" "B.Paste")
			(roundrect_rratio 0.25)
			(net 193 "/FPGA MSSIO/BT_UART_TX")
			(pintype "passive")
		)
	)
)
